(kicad_pcb
	(version 20260206)
	(generator "pcbnew")
	(generator_version "10.0")
	(general
		(thickness 1.6)
		(legacy_teardrops no)
	)
	(paper "A4")
	(title_block
		(title "Bryce Canyon_F.DPB_16315-1-OCP.brd")
		(comment 1 "Bryce Canyon / footprints 2017-2024 of 2223")
	)
	(layers
		(0 "F.Cu" signal "TOP")
		(4 "In1.Cu" signal "L2GND")
		(6 "In2.Cu" signal "L3")
		(8 "In3.Cu" signal "L4GND")
		(10 "In4.Cu" signal "L5")
		(12 "In5.Cu" signal "L6VCC")
		(14 "In6.Cu" signal "L7VCC")
		(16 "In7.Cu" signal "L8")
		(18 "In8.Cu" signal "L9GND")
		(20 "In9.Cu" signal "L10")
		(22 "In10.Cu" signal "L11GND")
		(2 "B.Cu" signal "BOTTOM")
		(9 "F.Adhes" user "F.Adhesive")
		(11 "B.Adhes" user "B.Adhesive")
		(13 "F.Paste" user "Package Geometry/Pastemask Top")
		(15 "B.Paste" user "Package Geometry/Pastemask Bottom")
		(5 "F.SilkS" user "Ref Des/Silkscreen Top")
		(7 "B.SilkS" user "Ref Des/Silkscreen Bottom")
		(1 "F.Mask" user "Board Geometry/Soldermask Top")
		(3 "B.Mask" user "Board Geometry/Soldermask Bottom")
		(17 "Dwgs.User" user "User.Drawings")
		(19 "Cmts.User" user "User.Comments")
		(21 "Eco1.User" user "User.Eco1")
		(23 "Eco2.User" user "User.Eco2")
		(25 "Edge.Cuts" user "Board Geometry/Outline")
		(27 "Margin" user)
		(31 "F.CrtYd" user "Package Geometry/Place Bound Top")
		(29 "B.CrtYd" user "Package Geometry/Place Bound Bottom")
		(35 "F.Fab" user "Ref Des/Assembly Top")
		(33 "B.Fab" user "Ref Des/Assembly Bottom")
	)
	(footprint ""
		(layer "F.Cu")
		(at 372.0338 -146.5834 180)
		(property "Reference" "C560"
			(at 0 0 180)
			(layer "F.SilkS")
			(hide yes)
			(effects
				(font
					(size 1.27 1.27)
				)
			)
		)
		(property "Value" "SC2D2U25V5KX-2-GP"
			(at -0.0762 -6.1214 180)
			(unlocked yes)
			(layer "F.Fab")
			(hide yes)
			(effects
				(font
					(size 1.016 1.016)
					(thickness 0.1524)
				)
			)
		)
		(property "Device Type" "C805H54"
			(at -0.0762 -8.1534 180)
			(unlocked yes)
			(layer "F.Fab")
			(hide yes)
			(effects
				(font
					(size 1.016 1.016)
					(thickness 0.1524)
				)
			)
		)
		(duplicate_pad_numbers_are_jumpers no)
		(fp_line
			(start 0.635 0)
			(end -0.635 0)
			(stroke
				(width 0.508)
				(type default)
			)
			(layer "F.SilkS")
		)
		(fp_rect
			(start -0.9652 1.778)
			(end 0.9652 -1.778)
			(stroke
				(width 0)
				(type default)
			)
			(fill no)
			(layer "F.CrtYd")
		)
		(fp_poly
			(pts
				(xy -0.9652 -1.778) (xy 0.9652 -1.778) (xy 0.9652 1.778) (xy -0.9652 1.778)
			)
			(stroke
				(width 0)
				(type default)
			)
			(fill no)
			(layer "F.Fab")
		)
		(pad "1" smd rect
			(at 0 -0.9652 180)
			(size 1.397 1.143)
			(layers "F.Cu" "F.Mask" "F.Paste")
			(net "COMP_B_PGOOD")
		)
		(pad "2" smd rect
			(at 0 0.9652 180)
			(size 1.397 1.143)
			(layers "F.Cu" "F.Mask" "F.Paste")
			(net "GND")
		)
	)
	(footprint ""
		(layer "F.Cu")
		(at 371.022118 -245.334282 -90)
		(property "Reference" "R484"
			(at 0 0 270)
			(layer "F.SilkS")
			(hide yes)
			(effects
				(font
					(size 1.27 1.27)
				)
			)
		)
		(property "Value" "4K7R2J-2-GP"
			(at 0.064008 -3.993896 270)
			(unlocked yes)
			(layer "F.Fab")
			(hide yes)
			(effects
				(font
					(size 1.016 1.016)
					(thickness 0.1524)
				)
			)
		)
		(property "Device Type" "R402H16"
			(at 0.064008 -5.517896 270)
			(unlocked yes)
			(layer "F.Fab")
			(hide yes)
			(effects
				(font
					(size 1.016 1.016)
					(thickness 0.1524)
				)
			)
		)
		(duplicate_pad_numbers_are_jumpers no)
		(fp_line
			(start -0.508 -0.9398)
			(end -0.508 0.9398)
			(stroke
				(width 0.1524)
				(type default)
			)
			(layer "F.SilkS")
		)
		(fp_line
			(start 0.508 -0.9398)
			(end -0.508 -0.9398)
			(stroke
				(width 0.1524)
				(type default)
			)
			(layer "F.SilkS")
		)
		(fp_rect
			(start -0.508 0.9398)
			(end 0.508 -0.9398)
			(stroke
				(width 0)
				(type default)
			)
			(fill no)
			(layer "F.CrtYd")
		)
		(fp_rect
			(start -0.508 0.9398)
			(end 0.508 -0.9398)
			(stroke
				(width 0)
				(type default)
			)
			(fill no)
			(layer "F.Fab")
		)
		(pad "1" smd custom
			(at 0 -0.4445 270)
			(size 0.1397 0.1397)
			(layers "F.Cu" "F.Mask" "F.Paste")
			(net "DRIVE_A_8_ACT")
			(options
				(clearance outline)
				(anchor circle)
			)
			(primitives
				(gr_poly
					(pts
						(arc
							(start -0.1778 -0.2794)
							(mid -0.249642 -0.249642)
							(end -0.2794 -0.1778)
						)
						(arc
							(start -0.2794 0.1778)
							(mid -0.249642 0.249642)
							(end -0.1778 0.2794)
						)
						(arc
							(start 0.1778 0.2794)
							(mid 0.249642 0.249642)
							(end 0.2794 0.1778)
						)
						(arc
							(start 0.2794 -0.1778)
							(mid 0.249642 -0.249642)
							(end 0.1778 -0.2794)
						)
					)
					(width 0)
					(fill yes)
				)
			)
		)
		(pad "2" smd custom
			(at 0 0.4445 270)
			(size 0.1397 0.1397)
			(layers "F.Cu" "F.Mask" "F.Paste")
			(net "GND")
			(options
				(clearance outline)
				(anchor circle)
			)
			(primitives
				(gr_poly
					(pts
						(arc
							(start -0.1778 -0.2794)
							(mid -0.249642 -0.249642)
							(end -0.2794 -0.1778)
						)
						(arc
							(start -0.2794 0.1778)
							(mid -0.249642 0.249642)
							(end -0.1778 0.2794)
						)
						(arc
							(start 0.1778 0.2794)
							(mid 0.249642 0.249642)
							(end 0.2794 0.1778)
						)
						(arc
							(start 0.2794 -0.1778)
							(mid 0.249642 -0.249642)
							(end 0.1778 -0.2794)
						)
					)
					(width 0)
					(fill yes)
				)
			)
		)
	)
	(footprint ""
		(layer "F.Cu")
		(at 235.761276 -349.211392 180)
		(property "Reference" "C8"
			(at 0 0 180)
			(layer "F.SilkS")
			(hide yes)
			(effects
				(font
					(size 1.27 1.27)
				)
			)
		)
		(property "Value" "SCD1U16V2KX-3GP"
			(at 1.1811 -2.7051 180)
			(unlocked yes)
			(layer "F.Fab")
			(hide yes)
			(effects
				(font
					(size 1.016 1.016)
					(thickness 0.1524)
				)
			)
		)
		(property "Device Type" "C402H22"
			(at 1.1811 -4.2291 180)
			(unlocked yes)
			(layer "F.Fab")
			(hide yes)
			(effects
				(font
					(size 1.016 1.016)
					(thickness 0.1524)
				)
			)
		)
		(duplicate_pad_numbers_are_jumpers no)
		(fp_rect
			(start -0.4318 0.9525)
			(end 0.4318 -0.9525)
			(stroke
				(width 0)
				(type default)
			)
			(fill no)
			(layer "F.CrtYd")
		)
		(fp_rect
			(start -0.4318 0.9525)
			(end 0.4318 -0.9525)
			(stroke
				(width 0)
				(type default)
			)
			(fill no)
			(layer "F.Fab")
		)
		(pad "1" smd custom
			(at 0 -0.4445 180)
			(size 0.1524 0.1524)
			(layers "F.Cu" "F.Mask" "F.Paste")
			(net "P3V3_SENSE")
			(options
				(clearance outline)
				(anchor circle)
			)
			(primitives
				(gr_poly
					(pts
						(arc
							(start 0.3048 -0.2032)
							(mid 0.275042 -0.275042)
							(end 0.2032 -0.3048)
						)
						(arc
							(start -0.2032 -0.3048)
							(mid -0.275042 -0.275042)
							(end -0.3048 -0.2032)
						)
						(arc
							(start -0.3048 0.2032)
							(mid -0.275042 0.275042)
							(end -0.2032 0.3048)
						)
						(arc
							(start 0.2032 0.3048)
							(mid 0.275042 0.275042)
							(end 0.3048 0.2032)
						)
					)
					(width 0)
					(fill yes)
				)
			)
		)
		(pad "2" smd custom
			(at 0 0.4445 180)
			(size 0.1524 0.1524)
			(layers "F.Cu" "F.Mask" "F.Paste")
			(net "GND")
			(options
				(clearance outline)
				(anchor circle)
			)
			(primitives
				(gr_poly
					(pts
						(arc
							(start 0.3048 -0.2032)
							(mid 0.275042 -0.275042)
							(end 0.2032 -0.3048)
						)
						(arc
							(start -0.2032 -0.3048)
							(mid -0.275042 -0.275042)
							(end -0.3048 -0.2032)
						)
						(arc
							(start -0.3048 0.2032)
							(mid -0.275042 0.275042)
							(end -0.2032 0.3048)
						)
						(arc
							(start 0.2032 0.3048)
							(mid 0.275042 0.275042)
							(end 0.3048 0.2032)
						)
					)
					(width 0)
					(fill yes)
				)
			)
		)
	)
	(footprint ""
		(layer "F.Cu")
		(at 255.415034 -2.017522 90)
		(property "Reference" "TP215"
			(at 0 0 90)
			(layer "F.SilkS")
			(hide yes)
			(effects
				(font
					(size 1.27 1.27)
				)
			)
		)
		(property "Value" "TPAD32-GP"
			(at -0.0508 -1.6764 90)
			(unlocked yes)
			(layer "F.Fab")
			(hide yes)
			(effects
				(font
					(size 1.016 1.016)
					(thickness 0.1524)
				)
			)
		)
		(property "Device Type" "TPAD32"
			(at -0.0508 -3.2004 90)
			(unlocked yes)
			(layer "F.Fab")
			(hide yes)
			(effects
				(font
					(size 1.016 1.016)
					(thickness 0.1524)
				)
			)
		)
		(duplicate_pad_numbers_are_jumpers no)
		(fp_poly
			(pts
				(arc
					(start 0 0.4064)
					(mid 0 -0.4064)
					(end 0 0.4064)
				)
			)
			(stroke
				(width 0)
				(type default)
			)
			(fill no)
			(layer "F.CrtYd")
		)
		(fp_poly
			(pts
				(arc
					(start 0 0.7112)
					(mid 0 -0.7112)
					(end 0 0.7112)
				)
			)
			(stroke
				(width 0)
				(type default)
			)
			(fill no)
			(layer "F.Fab")
		)
		(pad "1" smd circle
			(at 0 0 90)
			(size 0.8128 0.8128)
			(layers "F.Cu" "F.Mask" "F.Paste")
			(net "TP_COMP_A_NCSI_RXD0")
		)
	)
	(footprint ""
		(layer "F.Cu")
		(at 233.172 -390.9568 -90)
		(property "Reference" "R1150"
			(at 0 0 270)
			(layer "F.SilkS")
			(hide yes)
			(effects
				(font
					(size 1.27 1.27)
				)
			)
		)
		(property "Value" "0R2J-2-GP"
			(at 0.064008 -3.993896 270)
			(unlocked yes)
			(layer "F.Fab")
			(hide yes)
			(effects
				(font
					(size 1.016 1.016)
					(thickness 0.1524)
				)
			)
		)
		(property "Device Type" "R402H16"
			(at 0.064008 -5.517896 270)
			(unlocked yes)
			(layer "F.Fab")
			(hide yes)
			(effects
				(font
					(size 1.016 1.016)
					(thickness 0.1524)
				)
			)
		)
		(duplicate_pad_numbers_are_jumpers no)
		(fp_line
			(start -0.508 -0.9398)
			(end -0.508 0.9398)
			(stroke
				(width 0.1524)
				(type default)
			)
			(layer "F.SilkS")
		)
		(fp_line
			(start 0.508 -0.9398)
			(end -0.508 -0.9398)
			(stroke
				(width 0.1524)
				(type default)
			)
			(layer "F.SilkS")
		)
		(fp_rect
			(start -0.508 0.9398)
			(end 0.508 -0.9398)
			(stroke
				(width 0)
				(type default)
			)
			(fill no)
			(layer "F.CrtYd")
		)
		(fp_rect
			(start -0.508 0.9398)
			(end 0.508 -0.9398)
			(stroke
				(width 0)
				(type default)
			)
			(fill no)
			(layer "F.Fab")
		)
		(pad "1" smd custom
			(at 0 -0.4445 270)
			(size 0.1397 0.1397)
			(layers "F.Cu" "F.Mask" "F.Paste")
			(net "MB3_SPISS_PD")
			(options
				(clearance outline)
				(anchor circle)
			)
			(primitives
				(gr_poly
					(pts
						(arc
							(start -0.1778 -0.2794)
							(mid -0.249642 -0.249642)
							(end -0.2794 -0.1778)
						)
						(arc
							(start -0.2794 0.1778)
							(mid -0.249642 0.249642)
							(end -0.1778 0.2794)
						)
						(arc
							(start 0.1778 0.2794)
							(mid 0.249642 0.249642)
							(end 0.2794 0.1778)
						)
						(arc
							(start 0.2794 -0.1778)
							(mid 0.249642 -0.249642)
							(end 0.1778 -0.2794)
						)
					)
					(width 0)
					(fill yes)
				)
			)
		)
		(pad "2" smd custom
			(at 0 0.4445 270)
			(size 0.1397 0.1397)
			(layers "F.Cu" "F.Mask" "F.Paste")
			(net "AGND_CURRENT_DPB")
			(options
				(clearance outline)
				(anchor circle)
			)
			(primitives
				(gr_poly
					(pts
						(arc
							(start -0.1778 -0.2794)
							(mid -0.249642 -0.249642)
							(end -0.2794 -0.1778)
						)
						(arc
							(start -0.2794 0.1778)
							(mid -0.249642 0.249642)
							(end -0.1778 0.2794)
						)
						(arc
							(start 0.1778 0.2794)
							(mid 0.249642 0.249642)
							(end 0.2794 0.1778)
						)
						(arc
							(start 0.2794 -0.1778)
							(mid 0.249642 -0.249642)
							(end 0.1778 -0.2794)
						)
					)
					(width 0)
					(fill yes)
				)
			)
		)
	)
	(footprint ""
		(layer "F.Cu")
		(at 469.942926 -53.457094 -90)
		(property "Reference" "R950"
			(at 0 0 270)
			(layer "F.SilkS")
			(hide yes)
			(effects
				(font
					(size 1.27 1.27)
				)
			)
		)
		(property "Value" "300KR2F-GP"
			(at 0.064008 -3.993896 270)
			(unlocked yes)
			(layer "F.Fab")
			(hide yes)
			(effects
				(font
					(size 1.016 1.016)
					(thickness 0.1524)
				)
			)
		)
		(property "Device Type" "R402H16"
			(at 0.064008 -5.517896 270)
			(unlocked yes)
			(layer "F.Fab")
			(hide yes)
			(effects
				(font
					(size 1.016 1.016)
					(thickness 0.1524)
				)
			)
		)
		(duplicate_pad_numbers_are_jumpers no)
		(fp_line
			(start -0.508 -0.9398)
			(end -0.508 0.9398)
			(stroke
				(width 0.1524)
				(type default)
			)
			(layer "F.SilkS")
		)
		(fp_line
			(start 0.508 -0.9398)
			(end -0.508 -0.9398)
			(stroke
				(width 0.1524)
				(type default)
			)
			(layer "F.SilkS")
		)
		(fp_rect
			(start -0.508 0.9398)
			(end 0.508 -0.9398)
			(stroke
				(width 0)
				(type default)
			)
			(fill no)
			(layer "F.CrtYd")
		)
		(fp_rect
			(start -0.508 0.9398)
			(end 0.508 -0.9398)
			(stroke
				(width 0)
				(type default)
			)
			(fill no)
			(layer "F.Fab")
		)
		(pad "1" smd custom
			(at 0 -0.4445 270)
			(size 0.1397 0.1397)
			(layers "F.Cu" "F.Mask" "F.Paste")
			(net "SW_HDD_N35")
			(options
				(clearance outline)
				(anchor circle)
			)
			(primitives
				(gr_poly
					(pts
						(arc
							(start -0.1778 -0.2794)
							(mid -0.249642 -0.249642)
							(end -0.2794 -0.1778)
						)
						(arc
							(start -0.2794 0.1778)
							(mid -0.249642 0.249642)
							(end -0.1778 0.2794)
						)
						(arc
							(start 0.1778 0.2794)
							(mid 0.249642 0.249642)
							(end 0.2794 0.1778)
						)
						(arc
							(start 0.2794 -0.1778)
							(mid 0.249642 -0.249642)
							(end 0.1778 -0.2794)
						)
					)
					(width 0)
					(fill yes)
				)
			)
		)
		(pad "2" smd custom
			(at 0 0.4445 270)
			(size 0.1397 0.1397)
			(layers "F.Cu" "F.Mask" "F.Paste")
			(net "P12V_A")
			(options
				(clearance outline)
				(anchor circle)
			)
			(primitives
				(gr_poly
					(pts
						(arc
							(start -0.1778 -0.2794)
							(mid -0.249642 -0.249642)
							(end -0.2794 -0.1778)
						)
						(arc
							(start -0.2794 0.1778)
							(mid -0.249642 0.249642)
							(end -0.1778 0.2794)
						)
						(arc
							(start 0.1778 0.2794)
							(mid 0.249642 0.249642)
							(end 0.2794 0.1778)
						)
						(arc
							(start 0.2794 -0.1778)
							(mid 0.249642 -0.249642)
							(end 0.1778 -0.2794)
						)
					)
					(width 0)
					(fill yes)
				)
			)
		)
	)
	(footprint ""
		(layer "F.Cu")
		(at 451.527164 -242.250976)
		(property "Reference" "R268"
			(at 0 0 0)
			(layer "F.SilkS")
			(hide yes)
			(effects
				(font
					(size 1.27 1.27)
				)
			)
		)
		(property "Value" "130R3F-GP"
			(at -0.0254 -2.5146 0)
			(unlocked yes)
			(layer "F.Fab")
			(hide yes)
			(effects
				(font
					(size 1.016 1.016)
					(thickness 0.1524)
				)
			)
		)
		(property "Device Type" "R603H22"
			(at -0.0254 -4.0386 0)
			(unlocked yes)
			(layer "F.Fab")
			(hide yes)
			(effects
				(font
					(size 1.016 1.016)
					(thickness 0.1524)
				)
			)
		)
		(duplicate_pad_numbers_are_jumpers no)
		(fp_line
			(start -0.4826 0)
			(end -0.2032 0)
			(stroke
				(width 0.2032)
				(type default)
			)
			(layer "F.SilkS")
		)
		(fp_line
			(start 0.2032 0)
			(end 0.4826 0)
			(stroke
				(width 0.2032)
				(type default)
			)
			(layer "F.SilkS")
		)
		(fp_rect
			(start -0.5842 1.3335)
			(end 0.5842 -1.3335)
			(stroke
				(width 0)
				(type default)
			)
			(fill no)
			(layer "F.CrtYd")
		)
		(fp_rect
			(start -0.5842 1.3335)
			(end 0.5842 -1.3335)
			(stroke
				(width 0)
				(type default)
			)
			(fill no)
			(layer "F.Fab")
		)
		(pad "1" smd custom
			(at 0 -0.762)
			(size 0.2159 0.2159)
			(layers "F.Cu" "F.Mask" "F.Paste")
			(net "P5V_A_3")
			(options
				(clearance outline)
				(anchor circle)
			)
			(primitives
				(gr_poly
					(pts
						(arc
							(start -0.3302 -0.4318)
							(mid -0.402042 -0.402042)
							(end -0.4318 -0.3302)
						)
						(arc
							(start -0.4318 0.3302)
							(mid -0.402042 0.402042)
							(end -0.3302 0.4318)
						)
						(arc
							(start 0.3302 0.4318)
							(mid 0.402042 0.402042)
							(end 0.4318 0.3302)
						)
						(arc
							(start 0.4318 -0.3302)
							(mid 0.402042 -0.402042)
							(end 0.3302 -0.4318)
						)
					)
					(width 0)
					(fill yes)
				)
			)
		)
		(pad "2" smd custom
			(at 0 0.762)
			(size 0.2159 0.2159)
			(layers "F.Cu" "F.Mask" "F.Paste")
			(net "FLT_HDD11")
			(options
				(clearance outline)
				(anchor circle)
			)
			(primitives
				(gr_poly
					(pts
						(arc
							(start -0.3302 -0.4318)
							(mid -0.402042 -0.402042)
							(end -0.4318 -0.3302)
						)
						(arc
							(start -0.4318 0.3302)
							(mid -0.402042 0.402042)
							(end -0.3302 0.4318)
						)
						(arc
							(start 0.3302 0.4318)
							(mid 0.402042 0.402042)
							(end 0.4318 0.3302)
						)
						(arc
							(start 0.4318 -0.3302)
							(mid 0.402042 -0.402042)
							(end 0.3302 -0.4318)
						)
					)
					(width 0)
					(fill yes)
				)
			)
		)
	)
	(footprint ""
		(layer "F.Cu")
		(at 16.824198 -53.177694 -90)
		(property "Reference" "C360"
			(at 0 0 270)
			(layer "F.SilkS")
			(hide yes)
			(effects
				(font
					(size 1.27 1.27)
				)
			)
		)
		(property "Value" "SCD033U25V2KX-GP"
			(at 1.1811 -2.7051 270)
			(unlocked yes)
			(layer "F.Fab")
			(hide yes)
			(effects
				(font
					(size 1.016 1.016)
					(thickness 0.1524)
				)
			)
		)
		(property "Device Type" "C402H22"
			(at 1.1811 -4.2291 270)
			(unlocked yes)
			(layer "F.Fab")
			(hide yes)
			(effects
				(font
					(size 1.016 1.016)
					(thickness 0.1524)
				)
			)
		)
		(duplicate_pad_numbers_are_jumpers no)
		(fp_rect
			(start -0.4318 0.9525)
			(end 0.4318 -0.9525)
			(stroke
				(width 0)
				(type default)
			)
			(fill no)
			(layer "F.CrtYd")
		)
		(fp_rect
			(start -0.4318 0.9525)
			(end 0.4318 -0.9525)
			(stroke
				(width 0)
				(type default)
			)
			(fill no)
			(layer "F.Fab")
		)
		(pad "1" smd custom
			(at 0 -0.4445 270)
			(size 0.1524 0.1524)
			(layers "F.Cu" "F.Mask" "F.Paste")
			(net "SW_HDD_P24")
			(options
				(clearance outline)
				(anchor circle)
			)
			(primitives
				(gr_poly
					(pts
						(arc
							(start 0.3048 -0.2032)
							(mid 0.275042 -0.275042)
							(end 0.2032 -0.3048)
						)
						(arc
							(start -0.2032 -0.3048)
							(mid -0.275042 -0.275042)
							(end -0.3048 -0.2032)
						)
						(arc
							(start -0.3048 0.2032)
							(mid -0.275042 0.275042)
							(end -0.2032 0.3048)
						)
						(arc
							(start 0.2032 0.3048)
							(mid 0.275042 0.275042)
							(end 0.3048 0.2032)
						)
					)
					(width 0)
					(fill yes)
				)
			)
		)
		(pad "2" smd custom
			(at 0 0.4445 270)
			(size 0.1524 0.1524)
			(layers "F.Cu" "F.Mask" "F.Paste")
			(net "GND")
			(options
				(clearance outline)
				(anchor circle)
			)
			(primitives
				(gr_poly
					(pts
						(arc
							(start 0.3048 -0.2032)
							(mid 0.275042 -0.275042)
							(end 0.2032 -0.3048)
						)
						(arc
							(start -0.2032 -0.3048)
							(mid -0.275042 -0.275042)
							(end -0.3048 -0.2032)
						)
						(arc
							(start -0.3048 0.2032)
							(mid -0.275042 0.275042)
							(end -0.2032 0.3048)
						)
						(arc
							(start 0.2032 0.3048)
							(mid 0.275042 0.275042)
							(end 0.3048 0.2032)
						)
					)
					(width 0)
					(fill yes)
				)
			)
		)
	)
)
